# SCM (Grand Teton) — schematic netlist excerpt (pin names and nets, part order shuffled) for the footprints in the layout excerpt that follows; sources: Cadence DE-HDL packaged netlist, KiCad conversion of 12092022_DA0F0TMDCD0_F0T_Management_Board_D_brd_V3_OCP.brd

R142  Q_RES  33.2 1% CHIP  pkg 0402LF  page 12 : A = SMB_BMC_MM6_R_SCL ; B = SMB_BMC_MM6_SCL
C7  Q_CAP  0.1UF 25V 10% X7R  pkg 0402  page 20 : A = P1V2_AUX ; B = GND

(kicad_pcb
	(version 20260206)
	(generator "pcbnew")
	(generator_version "10.0")
	(general
		(thickness 1.6)
		(legacy_teardrops no)
	)
	(paper "A4")
	(title_block
		(title "12092022_DA0F0TMDCD0_F0T_Management_Board_D_brd_V3_OCP.brd")
		(comment 1 "Grand Teton / footprints 923-924 of 1440")
	)
	(layers
		(0 "F.Cu" signal "TOP")
		(4 "In1.Cu" signal "GND")
		(6 "In2.Cu" signal "IN1")
		(8 "In3.Cu" signal "GND1")
		(10 "In4.Cu" signal "IN2")
		(12 "In5.Cu" signal "VCC")
		(14 "In6.Cu" signal "VCC1")
		(16 "In7.Cu" signal "IN3")
		(18 "In8.Cu" signal "GND2")
		(20 "In9.Cu" signal "IN4")
		(22 "In10.Cu" signal "GND3")
		(2 "B.Cu" signal "BOTTOM")
		(9 "F.Adhes" user "F.Adhesive")
		(11 "B.Adhes" user "B.Adhesive")
		(13 "F.Paste" user "Package Geometry/Pastemask Top")
		(15 "B.Paste" user "Package Geometry/Pastemask Bottom")
		(5 "F.SilkS" user "Ref Des/Silkscreen Top")
		(7 "B.SilkS" user "Ref Des/Silkscreen Bottom")
		(1 "F.Mask" user "Board Geometry/Soldermask Top")
		(3 "B.Mask" user "Board Geometry/Soldermask Bottom")
		(17 "Dwgs.User" user "User.Drawings")
		(19 "Cmts.User" user "User.Comments")
		(21 "Eco1.User" user "User.Eco1")
		(23 "Eco2.User" user "User.Eco2")
		(25 "Edge.Cuts" user "Board Geometry/Outline")
		(27 "Margin" user)
		(31 "F.CrtYd" user "Package Geometry/Place Bound Top")
		(29 "B.CrtYd" user "Package Geometry/Place Bound Bottom")
		(35 "F.Fab" user "Ref Des/Assembly Top")
		(33 "B.Fab" user "Ref Des/Assembly Bottom")
	)
	(footprint ""
		(layer "B.Cu")
		(at 59.563 -34.7218 90)
		(property "Reference" "R142"
			(at 0 0 90)
			(layer "B.SilkS")
			(hide yes)
			(effects
				(font
					(size 1.27 1.27)
				)
				(justify mirror)
			)
		)
		(property "Value" ""
			(at 0 0 90)
			(layer "B.Fab")
			(effects
				(font
					(size 1.27 1.27)
				)
				(justify mirror)
			)
		)
		(duplicate_pad_numbers_are_jumpers no)
		(fp_line
			(start 0.7874 -0.4064)
			(end -0.7874 -0.4064)
			(stroke
				(width 0.1524)
				(type default)
			)
			(layer "B.SilkS")
		)
		(fp_line
			(start -0.7874 -0.4064)
			(end -0.7874 0.4064)
			(stroke
				(width 0.1524)
				(type default)
			)
			(layer "B.SilkS")
		)
		(fp_line
			(start 0.7874 0.4064)
			(end 0.7874 -0.4064)
			(stroke
				(width 0.1524)
				(type default)
			)
			(layer "B.SilkS")
		)
		(fp_line
			(start -0.7874 0.4064)
			(end 0.7874 0.4064)
			(stroke
				(width 0.1524)
				(type default)
			)
			(layer "B.SilkS")
		)
		(fp_line
			(start 0.67945 -0.305054)
			(end 0.12065 -0.305054)
			(stroke
				(width 0.1)
				(type default)
			)
			(layer "B.Fab")
		)
		(fp_line
			(start 0.12065 -0.305054)
			(end 0.12065 -0.2794)
			(stroke
				(width 0.1)
				(type default)
			)
			(layer "B.Fab")
		)
		(fp_line
			(start -0.12065 -0.3048)
			(end -0.67945 -0.3048)
			(stroke
				(width 0.1)
				(type default)
			)
			(layer "B.Fab")
		)
		(fp_line
			(start -0.67945 -0.3048)
			(end -0.67945 0.3048)
			(stroke
				(width 0.1)
				(type default)
			)
			(layer "B.Fab")
		)
		(fp_line
			(start 0.12065 -0.2794)
			(end -0.12065 -0.2794)
			(stroke
				(width 0.1)
				(type default)
			)
			(layer "B.Fab")
		)
		(fp_line
			(start -0.12065 -0.2794)
			(end -0.12065 -0.3048)
			(stroke
				(width 0.1)
				(type default)
			)
			(layer "B.Fab")
		)
		(fp_line
			(start 0.12065 0.2794)
			(end 0.12065 0.3048)
			(stroke
				(width 0.1)
				(type default)
			)
			(layer "B.Fab")
		)
		(fp_line
			(start -0.120396 0.2794)
			(end 0.12065 0.2794)
			(stroke
				(width 0.1)
				(type default)
			)
			(layer "B.Fab")
		)
		(fp_line
			(start 0.67945 0.3048)
			(end 0.67945 -0.305054)
			(stroke
				(width 0.1)
				(type default)
			)
			(layer "B.Fab")
		)
		(fp_line
			(start 0.12065 0.3048)
			(end 0.67945 0.3048)
			(stroke
				(width 0.1)
				(type default)
			)
			(layer "B.Fab")
		)
		(fp_line
			(start -0.120396 0.3048)
			(end -0.120396 0.2794)
			(stroke
				(width 0.1)
				(type default)
			)
			(layer "B.Fab")
		)
		(fp_line
			(start -0.67945 0.3048)
			(end -0.120396 0.3048)
			(stroke
				(width 0.1)
				(type default)
			)
			(layer "B.Fab")
		)
		(pad "1" smd circle
			(at 0.40005 0 270)
			(size 0 0)
			(layers "B.Cu" "B.Mask" "B.Paste")
			(net "SMB_BMC_MM6_R_SCL")
		)
		(pad "2" smd circle
			(at -0.40005 0 270)
			(size 0 0)
			(layers "B.Cu" "B.Mask" "B.Paste")
			(net "SMB_BMC_MM6_SCL")
		)
	)
	(footprint ""
		(layer "B.Cu")
		(at 71.68896 -49.849786 -90)
		(property "Reference" "C7"
			(at 0 0 90)
			(layer "B.SilkS")
			(hide yes)
			(effects
				(font
					(size 1.27 1.27)
				)
				(justify mirror)
			)
		)
		(property "Value" ""
			(at 0 0 90)
			(layer "B.Fab")
			(effects
				(font
					(size 1.27 1.27)
				)
				(justify mirror)
			)
		)
		(duplicate_pad_numbers_are_jumpers no)
		(fp_line
			(start -0.7874 0.4064)
			(end 0.7874 0.4064)
			(stroke
				(width 0.1524)
				(type default)
			)
			(layer "B.SilkS")
		)
		(fp_line
			(start 0.7874 0.4064)
			(end 0.7874 -0.4064)
			(stroke
				(width 0.1524)
				(type default)
			)
			(layer "B.SilkS")
		)
		(fp_line
			(start -0.7874 -0.4064)
			(end -0.7874 0.4064)
			(stroke
				(width 0.1524)
				(type default)
			)
			(layer "B.SilkS")
		)
		(fp_line
			(start 0.7874 -0.4064)
			(end -0.7874 -0.4064)
			(stroke
				(width 0.1524)
				(type default)
			)
			(layer "B.SilkS")
		)
		(fp_line
			(start -0.67945 0.3048)
			(end -0.120396 0.3048)
			(stroke
				(width 0.1)
				(type default)
			)
			(layer "B.Fab")
		)
		(fp_line
			(start -0.120396 0.3048)
			(end -0.120396 0.2794)
			(stroke
				(width 0.1)
				(type default)
			)
			(layer "B.Fab")
		)
		(fp_line
			(start 0.12065 0.3048)
			(end 0.67945 0.3048)
			(stroke
				(width 0.1)
				(type default)
			)
			(layer "B.Fab")
		)
		(fp_line
			(start 0.67945 0.3048)
			(end 0.67945 -0.305054)
			(stroke
				(width 0.1)
				(type default)
			)
			(layer "B.Fab")
		)
		(fp_line
			(start -0.120396 0.2794)
			(end 0.12065 0.2794)
			(stroke
				(width 0.1)
				(type default)
			)
			(layer "B.Fab")
		)
		(fp_line
			(start 0.12065 0.2794)
			(end 0.12065 0.3048)
			(stroke
				(width 0.1)
				(type default)
			)
			(layer "B.Fab")
		)
		(fp_line
			(start -0.12065 -0.2794)
			(end -0.12065 -0.3048)
			(stroke
				(width 0.1)
				(type default)
			)
			(layer "B.Fab")
		)
		(fp_line
			(start 0.12065 -0.2794)
			(end -0.12065 -0.2794)
			(stroke
				(width 0.1)
				(type default)
			)
			(layer "B.Fab")
		)
		(fp_line
			(start -0.67945 -0.3048)
			(end -0.67945 0.3048)
			(stroke
				(width 0.1)
				(type default)
			)
			(layer "B.Fab")
		)
		(fp_line
			(start -0.12065 -0.3048)
			(end -0.67945 -0.3048)
			(stroke
				(width 0.1)
				(type default)
			)
			(layer "B.Fab")
		)
		(fp_line
			(start 0.12065 -0.305054)
			(end 0.12065 -0.2794)
			(stroke
				(width 0.1)
				(type default)
			)
			(layer "B.Fab")
		)
		(fp_line
			(start 0.67945 -0.305054)
			(end 0.12065 -0.305054)
			(stroke
				(width 0.1)
				(type default)
			)
			(layer "B.Fab")
		)
		(pad "1" smd circle
			(at 0.40005 0 90)
			(size 0 0)
			(layers "B.Cu" "B.Mask" "B.Paste")
			(net "P1V2_AUX")
		)
		(pad "2" smd circle
			(at -0.40005 0 90)
			(size 0 0)
			(layers "B.Cu" "B.Mask" "B.Paste")
			(net "GND")
		)
	)
)
